(kicad_pcb
	(version 20260206)
	(generator "pcbnew")
	(generator_version "10.0")
	(general
		(thickness 1.6)
		(legacy_teardrops no)
	)
	(paper "A4")
	(title_block
		(title "baseboard — 13948-1b.1110WZS1818.brd")
		(comment 1 "Honey Badger (Wiwynn) / footprints 829-835 of 2523")
	)
	(layers
		(0 "F.Cu" signal "TOP")
		(4 "In1.Cu" signal "L2GND")
		(6 "In2.Cu" signal "L3")
		(8 "In3.Cu" signal "L4VCC")
		(10 "In4.Cu" signal "L5VCC")
		(12 "In5.Cu" signal "L6")
		(14 "In6.Cu" signal "L7GND")
		(2 "B.Cu" signal "BOTTOM")
		(9 "F.Adhes" user "F.Adhesive")
		(11 "B.Adhes" user "B.Adhesive")
		(13 "F.Paste" user "Package Geometry/Pastemask Top")
		(15 "B.Paste" user "Package Geometry/Pastemask Bottom")
		(5 "F.SilkS" user "Ref Des/Silkscreen Top")
		(7 "B.SilkS" user "Ref Des/Silkscreen Bottom")
		(1 "F.Mask" user "Board Geometry/Soldermask Top")
		(3 "B.Mask" user "Board Geometry/Soldermask Bottom")
		(17 "Dwgs.User" user "User.Drawings")
		(19 "Cmts.User" user "User.Comments")
		(21 "Eco1.User" user "User.Eco1")
		(23 "Eco2.User" user "User.Eco2")
		(25 "Edge.Cuts" user "Board Geometry/Outline")
		(27 "Margin" user)
		(31 "F.CrtYd" user "Package Geometry/Place Bound Top")
		(29 "B.CrtYd" user "Package Geometry/Place Bound Bottom")
		(35 "F.Fab" user "Ref Des/Assembly Top")
		(33 "B.Fab" user "Ref Des/Assembly Bottom")
	)
	(footprint ""
		(layer "F.Cu")
		(at 99.949 -221.488 180)
		(property "Reference" "R643"
			(at 0 0 180)
			(layer "F.SilkS")
			(hide yes)
			(effects
				(font
					(size 1.27 1.27)
				)
			)
		)
		(property "Value" "4K7R2F-GP"
			(at 0.064008 -3.993896 180)
			(unlocked yes)
			(layer "F.Fab")
			(hide yes)
			(effects
				(font
					(size 1.016 1.016)
					(thickness 0.1524)
				)
			)
		)
		(property "Device Type" "R402H16"
			(at 0.064008 -5.517896 180)
			(unlocked yes)
			(layer "F.Fab")
			(hide yes)
			(effects
				(font
					(size 1.016 1.016)
					(thickness 0.1524)
				)
			)
		)
		(duplicate_pad_numbers_are_jumpers no)
		(fp_line
			(start 0.508 -0.9398)
			(end -0.508 -0.9398)
			(stroke
				(width 0.1524)
				(type default)
			)
			(layer "F.SilkS")
		)
		(fp_line
			(start -0.508 -0.9398)
			(end -0.508 0.9398)
			(stroke
				(width 0.1524)
				(type default)
			)
			(layer "F.SilkS")
		)
		(fp_rect
			(start -0.508 0.9398)
			(end 0.508 -0.9398)
			(stroke
				(width 0)
				(type default)
			)
			(fill no)
			(layer "F.CrtYd")
		)
		(fp_rect
			(start -0.508 0.9398)
			(end 0.508 -0.9398)
			(stroke
				(width 0)
				(type default)
			)
			(fill no)
			(layer "F.Fab")
		)
		(pad "1" smd custom
			(at 0 -0.4445 180)
			(size 0.1397 0.1397)
			(layers "F.Cu" "F.Mask" "F.Paste")
			(net "P3V3_STBY")
			(options
				(clearance outline)
				(anchor circle)
			)
			(primitives
				(gr_poly
					(pts
						(arc
							(start -0.1778 -0.2794)
							(mid -0.249642 -0.249642)
							(end -0.2794 -0.1778)
						)
						(arc
							(start -0.2794 0.1778)
							(mid -0.249642 0.249642)
							(end -0.1778 0.2794)
						)
						(arc
							(start 0.1778 0.2794)
							(mid 0.249642 0.249642)
							(end 0.2794 0.1778)
						)
						(arc
							(start 0.2794 -0.1778)
							(mid 0.249642 -0.249642)
							(end 0.1778 -0.2794)
						)
					)
					(width 0)
					(fill yes)
				)
			)
		)
		(pad "2" smd custom
			(at 0 0.4445 180)
			(size 0.1397 0.1397)
			(layers "F.Cu" "F.Mask" "F.Paste")
			(net "IO_EXP_HDD_FAULT_A1")
			(options
				(clearance outline)
				(anchor circle)
			)
			(primitives
				(gr_poly
					(pts
						(arc
							(start -0.1778 -0.2794)
							(mid -0.249642 -0.249642)
							(end -0.2794 -0.1778)
						)
						(arc
							(start -0.2794 0.1778)
							(mid -0.249642 0.249642)
							(end -0.1778 0.2794)
						)
						(arc
							(start 0.1778 0.2794)
							(mid 0.249642 0.249642)
							(end 0.2794 0.1778)
						)
						(arc
							(start 0.2794 -0.1778)
							(mid 0.249642 -0.249642)
							(end 0.1778 -0.2794)
						)
					)
					(width 0)
					(fill yes)
				)
			)
		)
	)
	(footprint ""
		(layer "F.Cu")
		(at 106.788966 -63.8556)
		(property "Reference" "SR688"
			(at 0 0 0)
			(layer "F.SilkS")
			(hide yes)
			(effects
				(font
					(size 1.27 1.27)
				)
			)
		)
		(property "Value" "4K7R2F-GP"
			(at 0.064008 -3.993896 0)
			(unlocked yes)
			(layer "F.Fab")
			(hide yes)
			(effects
				(font
					(size 1.016 1.016)
					(thickness 0.1524)
				)
			)
		)
		(property "Device Type" "R402H16"
			(at 0.064008 -5.517896 0)
			(unlocked yes)
			(layer "F.Fab")
			(hide yes)
			(effects
				(font
					(size 1.016 1.016)
					(thickness 0.1524)
				)
			)
		)
		(duplicate_pad_numbers_are_jumpers no)
		(fp_line
			(start -0.508 -0.9398)
			(end -0.508 0.9398)
			(stroke
				(width 0.1524)
				(type default)
			)
			(layer "F.SilkS")
		)
		(fp_line
			(start 0.508 -0.9398)
			(end -0.508 -0.9398)
			(stroke
				(width 0.1524)
				(type default)
			)
			(layer "F.SilkS")
		)
		(fp_rect
			(start -0.508 0.9398)
			(end 0.508 -0.9398)
			(stroke
				(width 0)
				(type default)
			)
			(fill no)
			(layer "F.CrtYd")
		)
		(fp_rect
			(start -0.508 0.9398)
			(end 0.508 -0.9398)
			(stroke
				(width 0)
				(type default)
			)
			(fill no)
			(layer "F.Fab")
		)
		(pad "1" smd custom
			(at 0 -0.4445)
			(size 0.1397 0.1397)
			(layers "F.Cu" "F.Mask" "F.Paste")
			(net "IOC_TRST_N")
			(options
				(clearance outline)
				(anchor circle)
			)
			(primitives
				(gr_poly
					(pts
						(arc
							(start -0.1778 -0.2794)
							(mid -0.249642 -0.249642)
							(end -0.2794 -0.1778)
						)
						(arc
							(start -0.2794 0.1778)
							(mid -0.249642 0.249642)
							(end -0.1778 0.2794)
						)
						(arc
							(start 0.1778 0.2794)
							(mid 0.249642 0.249642)
							(end 0.2794 0.1778)
						)
						(arc
							(start 0.2794 -0.1778)
							(mid 0.249642 -0.249642)
							(end 0.1778 -0.2794)
						)
					)
					(width 0)
					(fill yes)
				)
			)
		)
		(pad "2" smd custom
			(at 0 0.4445)
			(size 0.1397 0.1397)
			(layers "F.Cu" "F.Mask" "F.Paste")
			(net "GND")
			(options
				(clearance outline)
				(anchor circle)
			)
			(primitives
				(gr_poly
					(pts
						(arc
							(start -0.1778 -0.2794)
							(mid -0.249642 -0.249642)
							(end -0.2794 -0.1778)
						)
						(arc
							(start -0.2794 0.1778)
							(mid -0.249642 0.249642)
							(end -0.1778 0.2794)
						)
						(arc
							(start 0.1778 0.2794)
							(mid 0.249642 0.249642)
							(end 0.2794 0.1778)
						)
						(arc
							(start 0.2794 -0.1778)
							(mid 0.249642 -0.249642)
							(end 0.1778 -0.2794)
						)
					)
					(width 0)
					(fill yes)
				)
			)
		)
	)
	(footprint ""
		(layer "F.Cu")
		(at 324.866 -144.526 90)
		(property "Reference" "R1848"
			(at 0 0 90)
			(layer "F.SilkS")
			(hide yes)
			(effects
				(font
					(size 1.27 1.27)
				)
			)
		)
		(property "Value" "10MR3F-GP"
			(at -0.0254 -2.5146 90)
			(unlocked yes)
			(layer "F.Fab")
			(hide yes)
			(effects
				(font
					(size 1.016 1.016)
					(thickness 0.1524)
				)
			)
		)
		(property "Device Type" "R603H22"
			(at -0.0254 -4.0386 90)
			(unlocked yes)
			(layer "F.Fab")
			(hide yes)
			(effects
				(font
					(size 1.016 1.016)
					(thickness 0.1524)
				)
			)
		)
		(duplicate_pad_numbers_are_jumpers no)
		(fp_line
			(start 0.2032 0)
			(end 0.4826 0)
			(stroke
				(width 0.2032)
				(type default)
			)
			(layer "F.SilkS")
		)
		(fp_line
			(start -0.4826 0)
			(end -0.2032 0)
			(stroke
				(width 0.2032)
				(type default)
			)
			(layer "F.SilkS")
		)
		(fp_rect
			(start -0.5842 1.3335)
			(end 0.5842 -1.3335)
			(stroke
				(width 0)
				(type default)
			)
			(fill no)
			(layer "F.CrtYd")
		)
		(fp_rect
			(start -0.5842 1.3335)
			(end 0.5842 -1.3335)
			(stroke
				(width 0)
				(type default)
			)
			(fill no)
			(layer "F.Fab")
		)
		(pad "1" smd custom
			(at 0 -0.762 90)
			(size 0.2159 0.2159)
			(layers "F.Cu" "F.Mask" "F.Paste")
			(net "RTC_OSCI")
			(options
				(clearance outline)
				(anchor circle)
			)
			(primitives
				(gr_poly
					(pts
						(arc
							(start -0.3302 -0.4318)
							(mid -0.402042 -0.402042)
							(end -0.4318 -0.3302)
						)
						(arc
							(start -0.4318 0.3302)
							(mid -0.402042 0.402042)
							(end -0.3302 0.4318)
						)
						(arc
							(start 0.3302 0.4318)
							(mid 0.402042 0.402042)
							(end 0.4318 0.3302)
						)
						(arc
							(start 0.4318 -0.3302)
							(mid 0.402042 -0.402042)
							(end 0.3302 -0.4318)
						)
					)
					(width 0)
					(fill yes)
				)
			)
		)
		(pad "2" smd custom
			(at 0 0.762 90)
			(size 0.2159 0.2159)
			(layers "F.Cu" "F.Mask" "F.Paste")
			(net "RTC_OSCO")
			(options
				(clearance outline)
				(anchor circle)
			)
			(primitives
				(gr_poly
					(pts
						(arc
							(start -0.3302 -0.4318)
							(mid -0.402042 -0.402042)
							(end -0.4318 -0.3302)
						)
						(arc
							(start -0.4318 0.3302)
							(mid -0.402042 0.402042)
							(end -0.3302 0.4318)
						)
						(arc
							(start 0.3302 0.4318)
							(mid 0.402042 0.402042)
							(end 0.4318 0.3302)
						)
						(arc
							(start 0.4318 -0.3302)
							(mid 0.402042 -0.402042)
							(end 0.3302 -0.4318)
						)
					)
					(width 0)
					(fill yes)
				)
			)
		)
	)
	(footprint ""
		(layer "F.Cu")
		(at 289.56 -210.058 90)
		(property "Reference" "R231"
			(at 0 0 90)
			(layer "F.SilkS")
			(hide yes)
			(effects
				(font
					(size 1.27 1.27)
				)
			)
		)
		(property "Value" "1KR2F-3-GP"
			(at 0.064008 -3.993896 90)
			(unlocked yes)
			(layer "F.Fab")
			(hide yes)
			(effects
				(font
					(size 1.016 1.016)
					(thickness 0.1524)
				)
			)
		)
		(property "Device Type" "R402H16"
			(at 0.064008 -5.517896 90)
			(unlocked yes)
			(layer "F.Fab")
			(hide yes)
			(effects
				(font
					(size 1.016 1.016)
					(thickness 0.1524)
				)
			)
		)
		(duplicate_pad_numbers_are_jumpers no)
		(fp_line
			(start 0.508 -0.9398)
			(end -0.508 -0.9398)
			(stroke
				(width 0.1524)
				(type default)
			)
			(layer "F.SilkS")
		)
		(fp_line
			(start -0.508 -0.9398)
			(end -0.508 0.9398)
			(stroke
				(width 0.1524)
				(type default)
			)
			(layer "F.SilkS")
		)
		(fp_rect
			(start -0.508 0.9398)
			(end 0.508 -0.9398)
			(stroke
				(width 0)
				(type default)
			)
			(fill no)
			(layer "F.CrtYd")
		)
		(fp_rect
			(start -0.508 0.9398)
			(end 0.508 -0.9398)
			(stroke
				(width 0)
				(type default)
			)
			(fill no)
			(layer "F.Fab")
		)
		(pad "1" smd custom
			(at 0 -0.4445 90)
			(size 0.1397 0.1397)
			(layers "F.Cu" "F.Mask" "F.Paste")
			(net "P1V53_STBY")
			(options
				(clearance outline)
				(anchor circle)
			)
			(primitives
				(gr_poly
					(pts
						(arc
							(start -0.1778 -0.2794)
							(mid -0.249642 -0.249642)
							(end -0.2794 -0.1778)
						)
						(arc
							(start -0.2794 0.1778)
							(mid -0.249642 0.249642)
							(end -0.1778 0.2794)
						)
						(arc
							(start 0.1778 0.2794)
							(mid 0.249642 0.249642)
							(end 0.2794 0.1778)
						)
						(arc
							(start 0.2794 -0.1778)
							(mid 0.249642 -0.249642)
							(end 0.1778 -0.2794)
						)
					)
					(width 0)
					(fill yes)
				)
			)
		)
		(pad "2" smd custom
			(at 0 0.4445 90)
			(size 0.1397 0.1397)
			(layers "F.Cu" "F.Mask" "F.Paste")
			(net "DDR_VREF")
			(options
				(clearance outline)
				(anchor circle)
			)
			(primitives
				(gr_poly
					(pts
						(arc
							(start -0.1778 -0.2794)
							(mid -0.249642 -0.249642)
							(end -0.2794 -0.1778)
						)
						(arc
							(start -0.2794 0.1778)
							(mid -0.249642 0.249642)
							(end -0.1778 0.2794)
						)
						(arc
							(start 0.1778 0.2794)
							(mid 0.249642 0.249642)
							(end 0.2794 0.1778)
						)
						(arc
							(start 0.2794 -0.1778)
							(mid 0.249642 -0.249642)
							(end 0.1778 -0.2794)
						)
					)
					(width 0)
					(fill yes)
				)
			)
		)
	)
	(footprint ""
		(layer "F.Cu")
		(at 184.404 -228.346 90)
		(property "Reference" "R1580"
			(at 0 0 90)
			(layer "F.SilkS")
			(hide yes)
			(effects
				(font
					(size 1.27 1.27)
				)
			)
		)
		(property "Value" "33R2F-3-GP"
			(at 0.064008 -3.993896 90)
			(unlocked yes)
			(layer "F.Fab")
			(hide yes)
			(effects
				(font
					(size 1.016 1.016)
					(thickness 0.1524)
				)
			)
		)
		(property "Device Type" "R402H16"
			(at 0.064008 -5.517896 90)
			(unlocked yes)
			(layer "F.Fab")
			(hide yes)
			(effects
				(font
					(size 1.016 1.016)
					(thickness 0.1524)
				)
			)
		)
		(duplicate_pad_numbers_are_jumpers no)
		(fp_line
			(start 0.508 -0.9398)
			(end -0.508 -0.9398)
			(stroke
				(width 0.1524)
				(type default)
			)
			(layer "F.SilkS")
		)
		(fp_line
			(start -0.508 -0.9398)
			(end -0.508 0.9398)
			(stroke
				(width 0.1524)
				(type default)
			)
			(layer "F.SilkS")
		)
		(fp_rect
			(start -0.508 0.9398)
			(end 0.508 -0.9398)
			(stroke
				(width 0)
				(type default)
			)
			(fill no)
			(layer "F.CrtYd")
		)
		(fp_rect
			(start -0.508 0.9398)
			(end 0.508 -0.9398)
			(stroke
				(width 0)
				(type default)
			)
			(fill no)
			(layer "F.Fab")
		)
		(pad "1" smd custom
			(at 0 -0.4445 90)
			(size 0.1397 0.1397)
			(layers "F.Cu" "F.Mask" "F.Paste")
			(net "FP_PWR_BTN_N")
			(options
				(clearance outline)
				(anchor circle)
			)
			(primitives
				(gr_poly
					(pts
						(arc
							(start -0.1778 -0.2794)
							(mid -0.249642 -0.249642)
							(end -0.2794 -0.1778)
						)
						(arc
							(start -0.2794 0.1778)
							(mid -0.249642 0.249642)
							(end -0.1778 0.2794)
						)
						(arc
							(start 0.1778 0.2794)
							(mid 0.249642 0.249642)
							(end 0.2794 0.1778)
						)
						(arc
							(start 0.2794 -0.1778)
							(mid 0.249642 -0.249642)
							(end 0.1778 -0.2794)
						)
					)
					(width 0)
					(fill yes)
				)
			)
		)
		(pad "2" smd custom
			(at 0 0.4445 90)
			(size 0.1397 0.1397)
			(layers "F.Cu" "F.Mask" "F.Paste")
			(net "FP_PWRBTN_RC_N")
			(options
				(clearance outline)
				(anchor circle)
			)
			(primitives
				(gr_poly
					(pts
						(arc
							(start -0.1778 -0.2794)
							(mid -0.249642 -0.249642)
							(end -0.2794 -0.1778)
						)
						(arc
							(start -0.2794 0.1778)
							(mid -0.249642 0.249642)
							(end -0.1778 0.2794)
						)
						(arc
							(start 0.1778 0.2794)
							(mid 0.249642 0.249642)
							(end 0.2794 0.1778)
						)
						(arc
							(start 0.2794 -0.1778)
							(mid 0.249642 -0.249642)
							(end 0.1778 -0.2794)
						)
					)
					(width 0)
					(fill yes)
				)
			)
		)
	)
	(footprint ""
		(layer "F.Cu")
		(at 107.931966 -63.8556)
		(property "Reference" "SR681"
			(at 0 0 0)
			(layer "F.SilkS")
			(hide yes)
			(effects
				(font
					(size 1.27 1.27)
				)
			)
		)
		(property "Value" "10KR2F-2-GP"
			(at 0.064008 -3.993896 0)
			(unlocked yes)
			(layer "F.Fab")
			(hide yes)
			(effects
				(font
					(size 1.016 1.016)
					(thickness 0.1524)
				)
			)
		)
		(property "Device Type" "R402H16"
			(at 0.064008 -5.517896 0)
			(unlocked yes)
			(layer "F.Fab")
			(hide yes)
			(effects
				(font
					(size 1.016 1.016)
					(thickness 0.1524)
				)
			)
		)
		(duplicate_pad_numbers_are_jumpers no)
		(fp_line
			(start -0.508 -0.9398)
			(end -0.508 0.9398)
			(stroke
				(width 0.1524)
				(type default)
			)
			(layer "F.SilkS")
		)
		(fp_line
			(start 0.508 -0.9398)
			(end -0.508 -0.9398)
			(stroke
				(width 0.1524)
				(type default)
			)
			(layer "F.SilkS")
		)
		(fp_rect
			(start -0.508 0.9398)
			(end 0.508 -0.9398)
			(stroke
				(width 0)
				(type default)
			)
			(fill no)
			(layer "F.CrtYd")
		)
		(fp_rect
			(start -0.508 0.9398)
			(end 0.508 -0.9398)
			(stroke
				(width 0)
				(type default)
			)
			(fill no)
			(layer "F.Fab")
		)
		(pad "1" smd custom
			(at 0 -0.4445)
			(size 0.1397 0.1397)
			(layers "F.Cu" "F.Mask" "F.Paste")
			(net "LSI_SCAN_EN")
			(options
				(clearance outline)
				(anchor circle)
			)
			(primitives
				(gr_poly
					(pts
						(arc
							(start -0.1778 -0.2794)
							(mid -0.249642 -0.249642)
							(end -0.2794 -0.1778)
						)
						(arc
							(start -0.2794 0.1778)
							(mid -0.249642 0.249642)
							(end -0.1778 0.2794)
						)
						(arc
							(start 0.1778 0.2794)
							(mid 0.249642 0.249642)
							(end 0.2794 0.1778)
						)
						(arc
							(start 0.2794 -0.1778)
							(mid 0.249642 -0.249642)
							(end 0.1778 -0.2794)
						)
					)
					(width 0)
					(fill yes)
				)
			)
		)
		(pad "2" smd custom
			(at 0 0.4445)
			(size 0.1397 0.1397)
			(layers "F.Cu" "F.Mask" "F.Paste")
			(net "GND")
			(options
				(clearance outline)
				(anchor circle)
			)
			(primitives
				(gr_poly
					(pts
						(arc
							(start -0.1778 -0.2794)
							(mid -0.249642 -0.249642)
							(end -0.2794 -0.1778)
						)
						(arc
							(start -0.2794 0.1778)
							(mid -0.249642 0.249642)
							(end -0.1778 0.2794)
						)
						(arc
							(start 0.1778 0.2794)
							(mid 0.249642 0.249642)
							(end 0.2794 0.1778)
						)
						(arc
							(start 0.2794 -0.1778)
							(mid 0.249642 -0.249642)
							(end 0.1778 -0.2794)
						)
					)
					(width 0)
					(fill yes)
				)
			)
		)
	)
	(footprint ""
		(layer "F.Cu")
		(at 329.556872 -214.702136 180)
		(property "Reference" "R182"
			(at 0 0 180)
			(layer "F.SilkS")
			(hide yes)
			(effects
				(font
					(size 1.27 1.27)
				)
			)
		)
		(property "Value" "0R2J-2-GP"
			(at 0.064008 -3.993896 180)
			(unlocked yes)
			(layer "F.Fab")
			(hide yes)
			(effects
				(font
					(size 1.016 1.016)
					(thickness 0.1524)
				)
			)
		)
		(property "Device Type" "R402H16"
			(at 0.064008 -5.517896 180)
			(unlocked yes)
			(layer "F.Fab")
			(hide yes)
			(effects
				(font
					(size 1.016 1.016)
					(thickness 0.1524)
				)
			)
		)
		(duplicate_pad_numbers_are_jumpers no)
		(fp_line
			(start 0.508 -0.9398)
			(end -0.508 -0.9398)
			(stroke
				(width 0.1524)
				(type default)
			)
			(layer "F.SilkS")
		)
		(fp_line
			(start -0.508 -0.9398)
			(end -0.508 0.9398)
			(stroke
				(width 0.1524)
				(type default)
			)
			(layer "F.SilkS")
		)
		(fp_rect
			(start -0.508 0.9398)
			(end 0.508 -0.9398)
			(stroke
				(width 0)
				(type default)
			)
			(fill no)
			(layer "F.CrtYd")
		)
		(fp_rect
			(start -0.508 0.9398)
			(end 0.508 -0.9398)
			(stroke
				(width 0)
				(type default)
			)
			(fill no)
			(layer "F.Fab")
		)
		(pad "1" smd custom
			(at 0 -0.4445 180)
			(size 0.1397 0.1397)
			(layers "F.Cu" "F.Mask" "F.Paste")
			(net "ADC_P1V8_STBY")
			(options
				(clearance outline)
				(anchor circle)
			)
			(primitives
				(gr_poly
					(pts
						(arc
							(start -0.1778 -0.2794)
							(mid -0.249642 -0.249642)
							(end -0.2794 -0.1778)
						)
						(arc
							(start -0.2794 0.1778)
							(mid -0.249642 0.249642)
							(end -0.1778 0.2794)
						)
						(arc
							(start 0.1778 0.2794)
							(mid 0.249642 0.249642)
							(end 0.2794 0.1778)
						)
						(arc
							(start 0.2794 -0.1778)
							(mid 0.249642 -0.249642)
							(end 0.1778 -0.2794)
						)
					)
					(width 0)
					(fill yes)
				)
			)
		)
		(pad "2" smd custom
			(at 0 0.4445 180)
			(size 0.1397 0.1397)
			(layers "F.Cu" "F.Mask" "F.Paste")
			(net "1V8_STBY_SENSE")
			(options
				(clearance outline)
				(anchor circle)
			)
			(primitives
				(gr_poly
					(pts
						(arc
							(start -0.1778 -0.2794)
							(mid -0.249642 -0.249642)
							(end -0.2794 -0.1778)
						)
						(arc
							(start -0.2794 0.1778)
							(mid -0.249642 0.249642)
							(end -0.1778 0.2794)
						)
						(arc
							(start 0.1778 0.2794)
							(mid 0.249642 0.249642)
							(end 0.2794 0.1778)
						)
						(arc
							(start 0.2794 -0.1778)
							(mid 0.249642 -0.249642)
							(end 0.1778 -0.2794)
						)
					)
					(width 0)
					(fill yes)
				)
			)
		)
	)
)
